(kicad_pcb
	(version 20221018)
	(generator pcbnew)
	(general
    (thickness 1.6)
  )
	(paper "A4")
	(title_block
    (title "NUC Computer Cluster Power Breakout HW")
    (date "2023-10-18")
    (rev "1.4.3")
    (company "Antmicro Ltd.")
		(comment 9 "footprints 125-132 of 234")
	)
	(layers
    (0 "F.Cu" mixed)
    (1 "In1.Cu" power)
    (2 "In2.Cu" mixed)
    (31 "B.Cu" power)
    (32 "B.Adhes" user "B.Adhesive")
    (33 "F.Adhes" user "F.Adhesive")
    (34 "B.Paste" user)
    (35 "F.Paste" user)
    (36 "B.SilkS" user "B.Silkscreen")
    (37 "F.SilkS" user "F.Silkscreen")
    (38 "B.Mask" user)
    (39 "F.Mask" user)
    (40 "Dwgs.User" user "User.Drawings")
    (41 "Cmts.User" user "User.Comments")
    (42 "Eco1.User" user "User.Eco1")
    (43 "Eco2.User" user "User.Eco2")
    (44 "Edge.Cuts" user)
    (45 "Margin" user)
    (46 "B.CrtYd" user "B.Courtyard")
    (47 "F.CrtYd" user "F.Courtyard")
    (48 "B.Fab" user)
    (49 "F.Fab" user)
  )
	(footprint "antmicro-footprints:FB_0603_1608Metric" (layer "F.Cu")
    (at 170.4 117.2)
    (property "Author" "Antmicro")
    (property "Current" "")
    (property "License" "Apache-2.0")
    (property "MPN" "BLM18AG601SN1D")
    (property "Manufacturer" "Murata")
    (property "Sheetfile" "ftdi-module.kicad_sch")
    (property "Sheetname" "FTDI")
    (property "Val" "600Z/0.5A")
    (property "ki_description" "Ferrite Bead, 0603 [1608 Metric], 600 ohm, 500 mA, BLM18A, 0.38 ohm, ± 25%, General use")
    (property "ki_keywords" "0603, SMT, FERRITE BEAD, PASSIVE")
    (attr smd)
    (fp_text reference "FB1" (at -0.95 -0.75) (layer "F.SilkS")
        (effects (font (size 0.7 0.7) (thickness 0.15)) (justify left bottom))
    )
    (fp_text value "FB_600Z_0.5A_Murata-BLM18AG_0603" (at 0 1.5) (layer "F.Fab")
        (effects (font (size 0.7 0.7) (thickness 0.15)) (justify left bottom))
    )
    (fp_text user "${REFERENCE}" (at -1.653 4.6) (layer "F.Fab") hide
        (effects (font (size 0.7 0.7) (thickness 0.15)) (justify left bottom))
    )
    (fp_text user "License: Apache-2.0" (at -1.653 5.9) (layer "F.Fab") hide
        (effects (font (size 0.7 0.7) (thickness 0.15)) (justify left bottom))
    )
    (fp_text user "Author: Antmicro" (at -1.653 3.162) (layer "F.Fab") hide
        (effects (font (size 0.7 0.7) (thickness 0.15)) (justify left bottom))
    )
    (fp_line (start -0.15 -0.4) (end 0.15 -0.4)
      (stroke (width 0.15) (type solid)) (layer "F.SilkS"))
    (fp_line (start -0.15 0.4) (end 0.15 0.4)
      (stroke (width 0.15) (type solid)) (layer "F.SilkS"))
    (fp_rect (start -1.25 -0.65) (end 1.25 0.65)
      (stroke (width 0.05) (type solid)) (fill none) (layer "F.CrtYd"))
    (fp_line (start -0.803 0.406) (end -0.803 -0.408)
      (stroke (width 0.15) (type solid)) (layer "F.Fab"))
    (fp_line (start 0.8 -0.408) (end -0.803 -0.408)
      (stroke (width 0.15) (type solid)) (layer "F.Fab"))
    (fp_line (start 0.8 -0.408) (end 0.8 0.406)
      (stroke (width 0.15) (type solid)) (layer "F.Fab"))
    (fp_line (start 0.8 0.406) (end -0.803 0.406)
      (stroke (width 0.15) (type solid)) (layer "F.Fab"))
    (pad "1" smd roundrect (at -0.7 0) (size 0.8 1) (layers "F.Cu" "F.Paste" "F.Mask") (roundrect_rratio 0.2)
      (net 6 "/FTDI/FTDI_VPLL") (pintype "passive"))
    (pad "2" smd roundrect (at 0.7 0) (size 0.8 1) (layers "F.Cu" "F.Paste" "F.Mask") (roundrect_rratio 0.2)
      (net 76 "VCC3V3_USB") (pintype "passive"))
  )
	(footprint "antmicro-footprints:C_0402_1005Metric" (layer "F.Cu")
    (at 154.5 119.915 90)
    (descr "Capacitor SMD 0402")
    (tags "capacitor SMD 0402")
    (property "Author" "Antmicro")
    (property "Dielectric" "X5R")
    (property "License" "Apache-2.0")
    (property "MPN" "GRM155R61H104KE14D")
    (property "Manufacturer" "Murata")
    (property "Sheetfile" "ftdi-module.kicad_sch")
    (property "Sheetname" "FTDI")
    (property "Val" "100n")
    (property "Voltage" "50V")
    (property "ki_description" "SMD Multilayer Ceramic Capacitor, 0.1 µF, 50 V, 0402 [1005 Metric], ± 10%, X5R, GRM Series")
    (property "ki_keywords" "0402, SMT, CAPACITOR, PASSIVE, CERAMIC, MLCC")
    (zone_connect 1)
    (attr smd)
    (fp_text reference "C4" (at -1.285 -0.6 90) (layer "F.SilkS")
        (effects (font (size 0.7 0.7) (thickness 0.15)) (justify left bottom))
    )
    (fp_text value "C_100n_0402" (at -1.022927 2.155213 90) (layer "F.Fab")
        (effects (font (size 0.7 0.7) (thickness 0.15)) (justify left bottom))
    )
    (fp_text user "${REFERENCE}" (at -0.939 4.599 90) (layer "F.Fab") hide
        (effects (font (size 0.7 0.7) (thickness 0.15)) (justify left bottom))
    )
    (fp_text user "Author: Antmicro" (at -0.939 3.399 90) (layer "F.Fab") hide
        (effects (font (size 0.7 0.7) (thickness 0.15)) (justify left bottom))
    )
    (fp_text user "License: Apache-2.0" (at -0.939 5.799 90) (layer "F.Fab") hide
        (effects (font (size 0.7 0.7) (thickness 0.15)) (justify left bottom))
    )
    (fp_rect (start -0.925 -0.47) (end 0.925 0.47)
      (stroke (width 0.05) (type default)) (fill none) (layer "F.CrtYd"))
    (fp_line (start -0.494 -0.25) (end 0.504 -0.25)
      (stroke (width 0.15) (type solid)) (layer "F.Fab"))
    (fp_line (start -0.494 0.248) (end -0.494 -0.25)
      (stroke (width 0.15) (type solid)) (layer "F.Fab"))
    (fp_line (start 0.504 -0.25) (end 0.504 0.248)
      (stroke (width 0.15) (type solid)) (layer "F.Fab"))
    (fp_line (start 0.504 0.248) (end -0.494 0.248)
      (stroke (width 0.15) (type solid)) (layer "F.Fab"))
    (pad "1" smd roundrect (at -0.48 0 90) (size 0.59 0.64) (layers "F.Cu" "F.Paste" "F.Mask") (roundrect_rratio 0.25)
      (net 77 "GNDD") (pintype "passive"))
    (pad "2" smd roundrect (at 0.48 0 90) (size 0.59 0.64) (layers "F.Cu" "F.Paste" "F.Mask") (roundrect_rratio 0.25)
      (net 76 "VCC3V3_USB") (pintype "passive"))
  )
	(footprint "antmicro-footprints:C_0402_1005Metric" (layer "F.Cu")
    (at 159.8 124.7)
    (descr "Capacitor SMD 0402")
    (tags "capacitor SMD 0402")
    (property "Author" "Antmicro")
    (property "Dielectric" "X5R")
    (property "License" "Apache-2.0")
    (property "MPN" "GRM155R61H104KE14D")
    (property "Manufacturer" "Murata")
    (property "Sheetfile" "ftdi-module.kicad_sch")
    (property "Sheetname" "FTDI")
    (property "Val" "100n")
    (property "Voltage" "50V")
    (property "ki_description" "SMD Multilayer Ceramic Capacitor, 0.1 µF, 50 V, 0402 [1005 Metric], ± 10%, X5R, GRM Series")
    (property "ki_keywords" "0402, SMT, CAPACITOR, PASSIVE, CERAMIC, MLCC")
    (zone_connect 1)
    (attr smd)
    (fp_text reference "C7" (at -0.65 1.45) (layer "F.SilkS")
        (effects (font (size 0.7 0.7) (thickness 0.15)) (justify left bottom))
    )
    (fp_text value "C_100n_0402" (at -1.022927 2.155213) (layer "F.Fab")
        (effects (font (size 0.7 0.7) (thickness 0.15)) (justify left bottom))
    )
    (fp_text user "${REFERENCE}" (at -0.939 4.599) (layer "F.Fab") hide
        (effects (font (size 0.7 0.7) (thickness 0.15)) (justify left bottom))
    )
    (fp_text user "License: Apache-2.0" (at -0.939 5.799) (layer "F.Fab") hide
        (effects (font (size 0.7 0.7) (thickness 0.15)) (justify left bottom))
    )
    (fp_text user "Author: Antmicro" (at -0.939 3.399) (layer "F.Fab") hide
        (effects (font (size 0.7 0.7) (thickness 0.15)) (justify left bottom))
    )
    (fp_rect (start -0.925 -0.47) (end 0.925 0.47)
      (stroke (width 0.05) (type default)) (fill none) (layer "F.CrtYd"))
    (fp_line (start -0.494 -0.25) (end 0.504 -0.25)
      (stroke (width 0.15) (type solid)) (layer "F.Fab"))
    (fp_line (start -0.494 0.248) (end -0.494 -0.25)
      (stroke (width 0.15) (type solid)) (layer "F.Fab"))
    (fp_line (start 0.504 -0.25) (end 0.504 0.248)
      (stroke (width 0.15) (type solid)) (layer "F.Fab"))
    (fp_line (start 0.504 0.248) (end -0.494 0.248)
      (stroke (width 0.15) (type solid)) (layer "F.Fab"))
    (pad "1" smd roundrect (at -0.48 0) (size 0.59 0.64) (layers "F.Cu" "F.Paste" "F.Mask") (roundrect_rratio 0.25)
      (net 77 "GNDD") (pintype "passive"))
    (pad "2" smd roundrect (at 0.48 0) (size 0.59 0.64) (layers "F.Cu" "F.Paste" "F.Mask") (roundrect_rratio 0.25)
      (net 76 "VCC3V3_USB") (pintype "passive"))
  )
	(footprint "antmicro-footprints:C_0402_1005Metric" (layer "F.Cu")
    (at 157.7 124.7 180)
    (descr "Capacitor SMD 0402")
    (tags "capacitor SMD 0402")
    (property "Author" "Antmicro")
    (property "Dielectric" "X5R")
    (property "License" "Apache-2.0")
    (property "MPN" "GRM155R61H104KE14D")
    (property "Manufacturer" "Murata")
    (property "Sheetfile" "ftdi-module.kicad_sch")
    (property "Sheetname" "FTDI")
    (property "Val" "100n")
    (property "Voltage" "50V")
    (property "ki_description" "SMD Multilayer Ceramic Capacitor, 0.1 µF, 50 V, 0402 [1005 Metric], ± 10%, X5R, GRM Series")
    (property "ki_keywords" "0402, SMT, CAPACITOR, PASSIVE, CERAMIC, MLCC")
    (zone_connect 1)
    (attr smd)
    (fp_text reference "C6" (at -1.5 -1.45) (layer "F.SilkS")
        (effects (font (size 0.7 0.7) (thickness 0.15)) (justify right bottom))
    )
    (fp_text value "C_100n_0402" (at -1.022927 2.155213) (layer "F.Fab")
        (effects (font (size 0.7 0.7) (thickness 0.15)) (justify right bottom))
    )
    (fp_text user "${REFERENCE}" (at -0.939 4.599) (layer "F.Fab") hide
        (effects (font (size 0.7 0.7) (thickness 0.15)) (justify right bottom))
    )
    (fp_text user "Author: Antmicro" (at -0.939 3.399) (layer "F.Fab") hide
        (effects (font (size 0.7 0.7) (thickness 0.15)) (justify right bottom))
    )
    (fp_text user "License: Apache-2.0" (at -0.939 5.799) (layer "F.Fab") hide
        (effects (font (size 0.7 0.7) (thickness 0.15)) (justify right bottom))
    )
    (fp_rect (start -0.925 -0.47) (end 0.925 0.47)
      (stroke (width 0.05) (type default)) (fill none) (layer "F.CrtYd"))
    (fp_line (start -0.494 -0.25) (end 0.504 -0.25)
      (stroke (width 0.15) (type solid)) (layer "F.Fab"))
    (fp_line (start -0.494 0.248) (end -0.494 -0.25)
      (stroke (width 0.15) (type solid)) (layer "F.Fab"))
    (fp_line (start 0.504 -0.25) (end 0.504 0.248)
      (stroke (width 0.15) (type solid)) (layer "F.Fab"))
    (fp_line (start 0.504 0.248) (end -0.494 0.248)
      (stroke (width 0.15) (type solid)) (layer "F.Fab"))
    (pad "1" smd roundrect (at -0.48 0 180) (size 0.59 0.64) (layers "F.Cu" "F.Paste" "F.Mask") (roundrect_rratio 0.25)
      (net 77 "GNDD") (pintype "passive"))
    (pad "2" smd roundrect (at 0.48 0 180) (size 0.59 0.64) (layers "F.Cu" "F.Paste" "F.Mask") (roundrect_rratio 0.25)
      (net 76 "VCC3V3_USB") (pintype "passive"))
  )
	(footprint "antmicro-footprints:R_0603_1608Metric" (layer "F.Cu")
    (at 165.4 114.8 90)
    (descr "Resistor SMD 0603")
    (tags "resistor SMD 0603")
    (property "Author" "Antmicro")
    (property "Current" "1A")
    (property "License" "Apache-2.0")
    (property "MPN" "CR0603-J/-000ELF")
    (property "Manufacturer" "Bourns")
    (property "Sheetfile" "ftdi-module.kicad_sch")
    (property "Sheetname" "FTDI")
    (property "Tolerance" "")
    (property "Val" "0R")
    (property "ki_description" "Zero Ohm Resistor, Jumper, 0603 [1608 Metric], Thick Film, 100 mW, 1 A, Surface Mount Device, CR")
    (property "ki_keywords" "0603, SMT, RESISTOR, PASSIVE")
    (attr smd)
    (fp_text reference "R4" (at 1.2 0.5 90) (layer "F.SilkS")
        (effects (font (size 0.7 0.7) (thickness 0.15)) (justify left bottom))
    )
    (fp_text value "R_0R_0603" (at 0 1.6 90) (layer "F.Fab")
        (effects (font (size 0.7 0.7) (thickness 0.15)) (justify left bottom))
    )
    (fp_text user "License: Apache-2.0" (at -1.25 5.9 90) (layer "F.Fab") hide
        (effects (font (size 0.7 0.7) (thickness 0.15)) (justify left bottom))
    )
    (fp_text user "${REFERENCE}" (at -1.25 3.898 90) (layer "F.Fab") hide
        (effects (font (size 0.7 0.7) (thickness 0.15)) (justify left bottom))
    )
    (fp_text user "Author: Antmicro" (at -1.25 4.9 90) (layer "F.Fab") hide
        (effects (font (size 0.7 0.7) (thickness 0.15)) (justify left bottom))
    )
    (fp_line (start -0.15 -0.4) (end 0.15 -0.4)
      (stroke (width 0.15) (type solid)) (layer "F.SilkS"))
    (fp_line (start -0.15 0.4) (end 0.15 0.4)
      (stroke (width 0.15) (type solid)) (layer "F.SilkS"))
    (fp_rect (start -1.25 -0.65) (end 1.25 0.65)
      (stroke (width 0.05) (type solid)) (fill none) (layer "F.CrtYd"))
    (fp_rect (start -0.8 -0.4) (end 0.8 0.4)
      (stroke (width 0.15) (type solid)) (fill none) (layer "F.Fab"))
    (pad "1" smd roundrect (at -0.7 0 90) (size 0.8 1) (layers "F.Cu" "F.Paste" "F.Mask") (roundrect_rratio 0.2)
      (net 9 "/FTDI/SDA_FTDI_2") (pintype "passive"))
    (pad "2" smd roundrect (at 0.7 0 90) (size 0.8 1) (layers "F.Cu" "F.Paste" "F.Mask") (roundrect_rratio 0.2)
      (net 80 "SDA_FTDI") (pintype "passive"))
  )
	(footprint "antmicro-footprints:C_0402_1005Metric" (layer "F.Cu")
    (at 174.3 102.05 180)
    (descr "Capacitor SMD 0402")
    (tags "capacitor SMD 0402")
    (property "Author" "Antmicro")
    (property "Dielectric" "X5R")
    (property "License" "Apache-2.0")
    (property "MPN" "GRM155R61H104KE14D")
    (property "Manufacturer" "Murata")
    (property "Sheetfile" "ftdi-module.kicad_sch")
    (property "Sheetname" "FTDI")
    (property "Val" "100n")
    (property "Voltage" "50V")
    (property "ki_description" "SMD Multilayer Ceramic Capacitor, 0.1 µF, 50 V, 0402 [1005 Metric], ± 10%, X5R, GRM Series")
    (property "ki_keywords" "0402, SMT, CAPACITOR, PASSIVE, CERAMIC, MLCC")
    (attr smd)
    (fp_text reference "C18" (at -0.075 0.975 180) (layer "F.SilkS")
        (effects (font (size 0.7 0.7) (thickness 0.15)))
    )
    (fp_text value "C_100n_0402" (at 0 1.17) (layer "F.Fab") hide
        (effects (font (size 1 1) (thickness 0.15)))
    )
    (fp_text user "Author: Antmicro" (at -0.939 3.399 180) (layer "F.Fab") hide
        (effects (font (size 0.7 0.7) (thickness 0.15)) (justify left bottom))
    )
    (fp_text user "${REFERENCE}" (at 0 0) (layer "F.Fab")
        (effects (font (size 0.25 0.25) (thickness 0.04)))
    )
    (fp_text user "License: Apache-2.0" (at -0.939 5.799 180) (layer "F.Fab") hide
        (effects (font (size 0.7 0.7) (thickness 0.15)) (justify left bottom))
    )
    (fp_rect (start -0.925 -0.47) (end 0.925 0.47)
      (stroke (width 0.05) (type default)) (fill none) (layer "F.CrtYd"))
    (fp_line (start -0.494 -0.25) (end 0.504 -0.25)
      (stroke (width 0.15) (type solid)) (layer "F.Fab"))
    (fp_line (start -0.494 0.248) (end -0.494 -0.25)
      (stroke (width 0.15) (type solid)) (layer "F.Fab"))
    (fp_line (start 0.504 -0.25) (end 0.504 0.248)
      (stroke (width 0.15) (type solid)) (layer "F.Fab"))
    (fp_line (start 0.504 0.248) (end -0.494 0.248)
      (stroke (width 0.15) (type solid)) (layer "F.Fab"))
    (pad "1" smd roundrect (at -0.48 0 180) (size 0.59 0.64) (layers "F.Cu" "F.Paste" "F.Mask") (roundrect_rratio 0.25)
      (net 1 "VCC3V3") (pintype "passive"))
    (pad "2" smd roundrect (at 0.48 0 180) (size 0.59 0.64) (layers "F.Cu" "F.Paste" "F.Mask") (roundrect_rratio 0.25)
      (net 4 "GND") (pintype "passive"))
  )
	(footprint "antmicro-footprints:C_0402_1005Metric" (layer "F.Cu")
    (at 155.6 124.7)
    (descr "Capacitor SMD 0402")
    (tags "capacitor SMD 0402")
    (property "Author" "Antmicro")
    (property "Dielectric" "X5R")
    (property "License" "Apache-2.0")
    (property "MPN" "GRM155R61H104KE14D")
    (property "Manufacturer" "Murata")
    (property "Sheetfile" "ftdi-module.kicad_sch")
    (property "Sheetname" "FTDI")
    (property "Val" "100n")
    (property "Voltage" "50V")
    (property "ki_description" "SMD Multilayer Ceramic Capacitor, 0.1 µF, 50 V, 0402 [1005 Metric], ± 10%, X5R, GRM Series")
    (property "ki_keywords" "0402, SMT, CAPACITOR, PASSIVE, CERAMIC, MLCC")
    (zone_connect 1)
    (attr smd)
    (fp_text reference "C8" (at -1.4 1.5) (layer "F.SilkS")
        (effects (font (size 0.7 0.7) (thickness 0.15)) (justify left bottom))
    )
    (fp_text value "C_100n_0402" (at -1.022927 2.155213) (layer "F.Fab")
        (effects (font (size 0.7 0.7) (thickness 0.15)) (justify left bottom))
    )
    (fp_text user "Author: Antmicro" (at -0.939 3.399) (layer "F.Fab") hide
        (effects (font (size 0.7 0.7) (thickness 0.15)) (justify left bottom))
    )
    (fp_text user "License: Apache-2.0" (at -0.939 5.799) (layer "F.Fab") hide
        (effects (font (size 0.7 0.7) (thickness 0.15)) (justify left bottom))
    )
    (fp_text user "${REFERENCE}" (at -0.939 4.599) (layer "F.Fab") hide
        (effects (font (size 0.7 0.7) (thickness 0.15)) (justify left bottom))
    )
    (fp_rect (start -0.925 -0.47) (end 0.925 0.47)
      (stroke (width 0.05) (type default)) (fill none) (layer "F.CrtYd"))
    (fp_line (start -0.494 -0.25) (end 0.504 -0.25)
      (stroke (width 0.15) (type solid)) (layer "F.Fab"))
    (fp_line (start -0.494 0.248) (end -0.494 -0.25)
      (stroke (width 0.15) (type solid)) (layer "F.Fab"))
    (fp_line (start 0.504 -0.25) (end 0.504 0.248)
      (stroke (width 0.15) (type solid)) (layer "F.Fab"))
    (fp_line (start 0.504 0.248) (end -0.494 0.248)
      (stroke (width 0.15) (type solid)) (layer "F.Fab"))
    (pad "1" smd roundrect (at -0.48 0) (size 0.59 0.64) (layers "F.Cu" "F.Paste" "F.Mask") (roundrect_rratio 0.25)
      (net 77 "GNDD") (pintype "passive"))
    (pad "2" smd roundrect (at 0.48 0) (size 0.59 0.64) (layers "F.Cu" "F.Paste" "F.Mask") (roundrect_rratio 0.25)
      (net 7 "1V8_FT") (pintype "passive"))
  )
	(footprint "antmicro-footprints:R_0402_1005Metric" (layer "F.Cu")
    (at 167.3 120.4 180)
    (descr "Resistor SMD 0402")
    (tags "resistor SMD 0402")
    (property "Author" "Antmicro")
    (property "License" "Apache-2.0")
    (property "MPN" "CR0402-FX-1202GLF")
    (property "Manufacturer" "Bourns")
    (property "Sheetfile" "ftdi-module.kicad_sch")
    (property "Sheetname" "FTDI")
    (property "Tolerance" "1%")
    (property "Val" "12k")
    (property "ki_description" "SMD Chip Resistor, 12 kohm, ± 1%, 62.5 mW, 0402 [1005 Metric], Thick Film, General Purpose")
    (property "ki_keywords" "0402, SMT, RESISTOR, PASSIVE")
    (attr smd)
    (fp_text reference "R3" (at 0.8 0.5 180) (layer "F.SilkS")
        (effects (font (size 0.7 0.7) (thickness 0.15)) (justify left bottom))
    )
    (fp_text value "R_12k_0402" (at -1.011843 1.772047 180) (layer "F.Fab")
        (effects (font (size 0.7 0.7) (thickness 0.15)) (justify left bottom))
    )
    (fp_text user "Author: Antmicro" (at -0.95 4.169 180) (layer "F.Fab") hide
        (effects (font (size 0.7 0.7) (thickness 0.15)) (justify left bottom))
    )
    (fp_text user "${REFERENCE}" (at -0.95 3.168 180) (layer "F.Fab") hide
        (effects (font (size 0.7 0.7) (thickness 0.15)) (justify left bottom))
    )
    (fp_text user "License: Apache-2.0" (at -0.95 5.169 180) (layer "F.Fab") hide
        (effects (font (size 0.7 0.7) (thickness 0.15)) (justify left bottom))
    )
    (fp_rect (start -0.925 -0.47) (end 0.925 0.47)
      (stroke (width 0.05) (type default)) (fill none) (layer "F.CrtYd"))
    (fp_rect (start -0.5 -0.25) (end 0.5 0.25)
      (stroke (width 0.15) (type solid)) (fill none) (layer "F.Fab"))
    (pad "1" smd roundrect (at -0.48 0 180) (size 0.59 0.64) (layers "F.Cu" "F.Paste" "F.Mask") (roundrect_rratio 0.25)
      (net 77 "GNDD") (pintype "passive"))
    (pad "2" smd roundrect (at 0.48 0 180) (size 0.59 0.64) (layers "F.Cu" "F.Paste" "F.Mask") (roundrect_rratio 0.25)
      (net 104 "Net-(U5-REF)") (pintype "passive"))
  )
)
